(kicad_pcb
	(version 20260206)
	(generator "pcbnew")
	(generator_version "10.0")
	(general
		(thickness 1.6)
		(legacy_teardrops no)
	)
	(paper "A4")
	(title_block
		(title "Bryce Canyon_SCC_16316-1_OCP.brd")
		(comment 1 "Bryce Canyon / footprints 1290-1297 of 1561")
	)
	(layers
		(0 "F.Cu" signal "TOP")
		(4 "In1.Cu" signal "L2GND")
		(6 "In2.Cu" signal "L3")
		(8 "In3.Cu" signal "L4VCC")
		(10 "In4.Cu" signal "L5VCC")
		(12 "In5.Cu" signal "L6")
		(14 "In6.Cu" signal "L7GND")
		(2 "B.Cu" signal "BOTTOM")
		(9 "F.Adhes" user "F.Adhesive")
		(11 "B.Adhes" user "B.Adhesive")
		(13 "F.Paste" user "Package Geometry/Pastemask Top")
		(15 "B.Paste" user "Package Geometry/Pastemask Bottom")
		(5 "F.SilkS" user "Ref Des/Silkscreen Top")
		(7 "B.SilkS" user "Ref Des/Silkscreen Bottom")
		(1 "F.Mask" user "Board Geometry/Soldermask Top")
		(3 "B.Mask" user "Board Geometry/Soldermask Bottom")
		(17 "Dwgs.User" user "User.Drawings")
		(19 "Cmts.User" user "User.Comments")
		(21 "Eco1.User" user "User.Eco1")
		(23 "Eco2.User" user "User.Eco2")
		(25 "Edge.Cuts" user "Board Geometry/Outline")
		(27 "Margin" user)
		(31 "F.CrtYd" user "Package Geometry/Place Bound Top")
		(29 "B.CrtYd" user "Package Geometry/Place Bound Bottom")
		(35 "F.Fab" user "Ref Des/Assembly Top")
		(33 "B.Fab" user "Ref Des/Assembly Bottom")
	)
	(footprint ""
		(layer "B.Cu")
		(at 123.2154 -39.4716 180)
		(property "Reference" "C54"
			(at 0 0 0)
			(layer "B.SilkS")
			(hide yes)
			(effects
				(font
					(size 1.27 1.27)
				)
				(justify mirror)
			)
		)
		(property "Value" "SCD01U16V1KX-GP"
			(at 2.8321 -1.7399 180)
			(unlocked yes)
			(layer "B.Fab")
			(hide yes)
			(effects
				(font
					(size 1.016 1.016)
					(thickness 0.1524)
				)
				(justify mirror)
			)
		)
		(property "Device Type" "C0201H13"
			(at 2.8321 -3.2639 180)
			(unlocked yes)
			(layer "B.Fab")
			(hide yes)
			(effects
				(font
					(size 1.016 1.016)
					(thickness 0.1524)
				)
				(justify mirror)
			)
		)
		(duplicate_pad_numbers_are_jumpers no)
		(fp_rect
			(start 0.2794 0.6477)
			(end -0.2794 -0.6477)
			(stroke
				(width 0)
				(type default)
			)
			(fill no)
			(layer "B.CrtYd")
		)
		(fp_rect
			(start 0.2794 0.6477)
			(end -0.2794 -0.6477)
			(stroke
				(width 0)
				(type default)
			)
			(fill no)
			(layer "B.Fab")
		)
		(pad "1" smd custom
			(at 0 -0.2794)
			(size 0.0762 0.0762)
			(layers "B.Cu" "B.Mask" "B.Paste")
			(net "PHY_DPB_TO_SCC_37_DN")
			(options
				(clearance outline)
				(anchor circle)
			)
			(primitives
				(gr_poly
					(pts
						(arc
							(start 0.1524 0.127)
							(mid 0.137521 0.162921)
							(end 0.1016 0.1778)
						)
						(arc
							(start -0.1016 0.1778)
							(mid -0.137521 0.162921)
							(end -0.1524 0.127)
						)
						(arc
							(start -0.1524 -0.127)
							(mid -0.137521 -0.162921)
							(end -0.1016 -0.1778)
						)
						(arc
							(start 0.1016 -0.1778)
							(mid 0.137521 -0.162921)
							(end 0.1524 -0.127)
						)
					)
					(width 0)
					(fill yes)
				)
			)
		)
		(pad "2" smd custom
			(at 0 0.2794)
			(size 0.0762 0.0762)
			(layers "B.Cu" "B.Mask" "B.Paste")
			(net "PHY_DPB_TO_SCC_C_37_DN")
			(options
				(clearance outline)
				(anchor circle)
			)
			(primitives
				(gr_poly
					(pts
						(arc
							(start 0.1524 0.127)
							(mid 0.137521 0.162921)
							(end 0.1016 0.1778)
						)
						(arc
							(start -0.1016 0.1778)
							(mid -0.137521 0.162921)
							(end -0.1524 0.127)
						)
						(arc
							(start -0.1524 -0.127)
							(mid -0.137521 -0.162921)
							(end -0.1016 -0.1778)
						)
						(arc
							(start 0.1016 -0.1778)
							(mid 0.137521 -0.162921)
							(end 0.1524 -0.127)
						)
					)
					(width 0)
					(fill yes)
				)
			)
		)
	)
	(footprint ""
		(layer "B.Cu")
		(at 108.61929 -61.183774)
		(property "Reference" "C129"
			(at 0 0 0)
			(layer "B.SilkS")
			(hide yes)
			(effects
				(font
					(size 1.27 1.27)
				)
				(justify mirror)
			)
		)
		(property "Value" "SCD1U6D3V1KX-GP"
			(at 2.8321 -1.7399 0)
			(unlocked yes)
			(layer "B.Fab")
			(hide yes)
			(effects
				(font
					(size 1.016 1.016)
					(thickness 0.1524)
				)
				(justify mirror)
			)
		)
		(property "Device Type" "C0201H13"
			(at 2.8321 -3.2639 0)
			(unlocked yes)
			(layer "B.Fab")
			(hide yes)
			(effects
				(font
					(size 1.016 1.016)
					(thickness 0.1524)
				)
				(justify mirror)
			)
		)
		(duplicate_pad_numbers_are_jumpers no)
		(fp_rect
			(start 0.2794 0.6477)
			(end -0.2794 -0.6477)
			(stroke
				(width 0)
				(type default)
			)
			(fill no)
			(layer "B.CrtYd")
		)
		(fp_rect
			(start 0.2794 0.6477)
			(end -0.2794 -0.6477)
			(stroke
				(width 0)
				(type default)
			)
			(fill no)
			(layer "B.Fab")
		)
		(pad "1" smd custom
			(at 0 -0.2794 180)
			(size 0.0762 0.0762)
			(layers "B.Cu" "B.Mask" "B.Paste")
			(net "P1V8_E")
			(options
				(clearance outline)
				(anchor circle)
			)
			(primitives
				(gr_poly
					(pts
						(arc
							(start 0.1524 0.127)
							(mid 0.137521 0.162921)
							(end 0.1016 0.1778)
						)
						(arc
							(start -0.1016 0.1778)
							(mid -0.137521 0.162921)
							(end -0.1524 0.127)
						)
						(arc
							(start -0.1524 -0.127)
							(mid -0.137521 -0.162921)
							(end -0.1016 -0.1778)
						)
						(arc
							(start 0.1016 -0.1778)
							(mid 0.137521 -0.162921)
							(end 0.1524 -0.127)
						)
					)
					(width 0)
					(fill yes)
				)
			)
		)
		(pad "2" smd custom
			(at 0 0.2794 180)
			(size 0.0762 0.0762)
			(layers "B.Cu" "B.Mask" "B.Paste")
			(net "GND")
			(options
				(clearance outline)
				(anchor circle)
			)
			(primitives
				(gr_poly
					(pts
						(arc
							(start 0.1524 0.127)
							(mid 0.137521 0.162921)
							(end 0.1016 0.1778)
						)
						(arc
							(start -0.1016 0.1778)
							(mid -0.137521 0.162921)
							(end -0.1524 0.127)
						)
						(arc
							(start -0.1524 -0.127)
							(mid -0.137521 -0.162921)
							(end -0.1016 -0.1778)
						)
						(arc
							(start 0.1016 -0.1778)
							(mid 0.137521 -0.162921)
							(end 0.1524 -0.127)
						)
					)
					(width 0)
					(fill yes)
				)
			)
		)
	)
	(footprint ""
		(layer "B.Cu")
		(at 101.219 -44.2214 180)
		(property "Reference" "C82"
			(at 0 0 0)
			(layer "B.SilkS")
			(hide yes)
			(effects
				(font
					(size 1.27 1.27)
				)
				(justify mirror)
			)
		)
		(property "Value" "SCD01U16V1KX-GP"
			(at 2.8321 -1.7399 180)
			(unlocked yes)
			(layer "B.Fab")
			(hide yes)
			(effects
				(font
					(size 1.016 1.016)
					(thickness 0.1524)
				)
				(justify mirror)
			)
		)
		(property "Device Type" "C0201H13"
			(at 2.8321 -3.2639 180)
			(unlocked yes)
			(layer "B.Fab")
			(hide yes)
			(effects
				(font
					(size 1.016 1.016)
					(thickness 0.1524)
				)
				(justify mirror)
			)
		)
		(duplicate_pad_numbers_are_jumpers no)
		(fp_rect
			(start 0.2794 0.6477)
			(end -0.2794 -0.6477)
			(stroke
				(width 0)
				(type default)
			)
			(fill no)
			(layer "B.CrtYd")
		)
		(fp_rect
			(start 0.2794 0.6477)
			(end -0.2794 -0.6477)
			(stroke
				(width 0)
				(type default)
			)
			(fill no)
			(layer "B.Fab")
		)
		(pad "1" smd custom
			(at 0 -0.2794)
			(size 0.0762 0.0762)
			(layers "B.Cu" "B.Mask" "B.Paste")
			(net "PHY_DPB_TO_SCC_19_DN")
			(options
				(clearance outline)
				(anchor circle)
			)
			(primitives
				(gr_poly
					(pts
						(arc
							(start 0.1524 0.127)
							(mid 0.137521 0.162921)
							(end 0.1016 0.1778)
						)
						(arc
							(start -0.1016 0.1778)
							(mid -0.137521 0.162921)
							(end -0.1524 0.127)
						)
						(arc
							(start -0.1524 -0.127)
							(mid -0.137521 -0.162921)
							(end -0.1016 -0.1778)
						)
						(arc
							(start 0.1016 -0.1778)
							(mid 0.137521 -0.162921)
							(end 0.1524 -0.127)
						)
					)
					(width 0)
					(fill yes)
				)
			)
		)
		(pad "2" smd custom
			(at 0 0.2794)
			(size 0.0762 0.0762)
			(layers "B.Cu" "B.Mask" "B.Paste")
			(net "PHY_DPB_TO_SCC_C_19_DN")
			(options
				(clearance outline)
				(anchor circle)
			)
			(primitives
				(gr_poly
					(pts
						(arc
							(start 0.1524 0.127)
							(mid 0.137521 0.162921)
							(end 0.1016 0.1778)
						)
						(arc
							(start -0.1016 0.1778)
							(mid -0.137521 0.162921)
							(end -0.1524 0.127)
						)
						(arc
							(start -0.1524 -0.127)
							(mid -0.137521 -0.162921)
							(end -0.1016 -0.1778)
						)
						(arc
							(start 0.1016 -0.1778)
							(mid 0.137521 -0.162921)
							(end 0.1524 -0.127)
						)
					)
					(width 0)
					(fill yes)
				)
			)
		)
	)
	(footprint ""
		(layer "B.Cu")
		(at 118.5418 -44.2214 180)
		(property "Reference" "C59"
			(at 0 0 0)
			(layer "B.SilkS")
			(hide yes)
			(effects
				(font
					(size 1.27 1.27)
				)
				(justify mirror)
			)
		)
		(property "Value" "SCD01U16V1KX-GP"
			(at 2.8321 -1.7399 180)
			(unlocked yes)
			(layer "B.Fab")
			(hide yes)
			(effects
				(font
					(size 1.016 1.016)
					(thickness 0.1524)
				)
				(justify mirror)
			)
		)
		(property "Device Type" "C0201H13"
			(at 2.8321 -3.2639 180)
			(unlocked yes)
			(layer "B.Fab")
			(hide yes)
			(effects
				(font
					(size 1.016 1.016)
					(thickness 0.1524)
				)
				(justify mirror)
			)
		)
		(duplicate_pad_numbers_are_jumpers no)
		(fp_rect
			(start 0.2794 0.6477)
			(end -0.2794 -0.6477)
			(stroke
				(width 0)
				(type default)
			)
			(fill no)
			(layer "B.CrtYd")
		)
		(fp_rect
			(start 0.2794 0.6477)
			(end -0.2794 -0.6477)
			(stroke
				(width 0)
				(type default)
			)
			(fill no)
			(layer "B.Fab")
		)
		(pad "1" smd custom
			(at 0 -0.2794)
			(size 0.0762 0.0762)
			(layers "B.Cu" "B.Mask" "B.Paste")
			(net "PHY_DPB_TO_SCC_34_DP")
			(options
				(clearance outline)
				(anchor circle)
			)
			(primitives
				(gr_poly
					(pts
						(arc
							(start 0.1524 0.127)
							(mid 0.137521 0.162921)
							(end 0.1016 0.1778)
						)
						(arc
							(start -0.1016 0.1778)
							(mid -0.137521 0.162921)
							(end -0.1524 0.127)
						)
						(arc
							(start -0.1524 -0.127)
							(mid -0.137521 -0.162921)
							(end -0.1016 -0.1778)
						)
						(arc
							(start 0.1016 -0.1778)
							(mid 0.137521 -0.162921)
							(end 0.1524 -0.127)
						)
					)
					(width 0)
					(fill yes)
				)
			)
		)
		(pad "2" smd custom
			(at 0 0.2794)
			(size 0.0762 0.0762)
			(layers "B.Cu" "B.Mask" "B.Paste")
			(net "PHY_DPB_TO_SCC_C_34_DP")
			(options
				(clearance outline)
				(anchor circle)
			)
			(primitives
				(gr_poly
					(pts
						(arc
							(start 0.1524 0.127)
							(mid 0.137521 0.162921)
							(end 0.1016 0.1778)
						)
						(arc
							(start -0.1016 0.1778)
							(mid -0.137521 0.162921)
							(end -0.1524 0.127)
						)
						(arc
							(start -0.1524 -0.127)
							(mid -0.137521 -0.162921)
							(end -0.1016 -0.1778)
						)
						(arc
							(start 0.1016 -0.1778)
							(mid 0.137521 -0.162921)
							(end 0.1524 -0.127)
						)
					)
					(width 0)
					(fill yes)
				)
			)
		)
	)
	(footprint ""
		(layer "B.Cu")
		(at 66.932048 -15.142972 90)
		(property "Reference" "C101"
			(at 0 0 90)
			(layer "B.SilkS")
			(hide yes)
			(effects
				(font
					(size 1.27 1.27)
				)
				(justify mirror)
			)
		)
		(property "Value" "SCD1U16V2KX-3GP"
			(at -1.1811 -2.7051 90)
			(unlocked yes)
			(layer "B.Fab")
			(hide yes)
			(effects
				(font
					(size 1.016 1.016)
					(thickness 0.1524)
				)
				(justify mirror)
			)
		)
		(property "Device Type" "C402H22"
			(at -1.1811 -4.2291 90)
			(unlocked yes)
			(layer "B.Fab")
			(hide yes)
			(effects
				(font
					(size 1.016 1.016)
					(thickness 0.1524)
				)
				(justify mirror)
			)
		)
		(duplicate_pad_numbers_are_jumpers no)
		(fp_rect
			(start 0.4318 0.9525)
			(end -0.4318 -0.9525)
			(stroke
				(width 0)
				(type default)
			)
			(fill no)
			(layer "B.CrtYd")
		)
		(fp_rect
			(start 0.4318 0.9525)
			(end -0.4318 -0.9525)
			(stroke
				(width 0)
				(type default)
			)
			(fill no)
			(layer "B.Fab")
		)
		(pad "1" smd custom
			(at 0 -0.4445 270)
			(size 0.1524 0.1524)
			(layers "B.Cu" "B.Mask" "B.Paste")
			(net "P1V8_E")
			(options
				(clearance outline)
				(anchor circle)
			)
			(primitives
				(gr_poly
					(pts
						(arc
							(start 0.3048 0.2032)
							(mid 0.275042 0.275042)
							(end 0.2032 0.3048)
						)
						(arc
							(start -0.2032 0.3048)
							(mid -0.275042 0.275042)
							(end -0.3048 0.2032)
						)
						(arc
							(start -0.3048 -0.2032)
							(mid -0.275042 -0.275042)
							(end -0.2032 -0.3048)
						)
						(arc
							(start 0.2032 -0.3048)
							(mid 0.275042 -0.275042)
							(end 0.3048 -0.2032)
						)
					)
					(width 0)
					(fill yes)
				)
			)
		)
		(pad "2" smd custom
			(at 0 0.4445 270)
			(size 0.1524 0.1524)
			(layers "B.Cu" "B.Mask" "B.Paste")
			(net "GND")
			(options
				(clearance outline)
				(anchor circle)
			)
			(primitives
				(gr_poly
					(pts
						(arc
							(start 0.3048 0.2032)
							(mid 0.275042 0.275042)
							(end 0.2032 0.3048)
						)
						(arc
							(start -0.2032 0.3048)
							(mid -0.275042 0.275042)
							(end -0.3048 0.2032)
						)
						(arc
							(start -0.3048 -0.2032)
							(mid -0.275042 -0.275042)
							(end -0.2032 -0.3048)
						)
						(arc
							(start 0.2032 -0.3048)
							(mid 0.275042 -0.275042)
							(end 0.3048 -0.2032)
						)
					)
					(width 0)
					(fill yes)
				)
			)
		)
	)
	(footprint ""
		(layer "B.Cu")
		(at 164.60089 -39.19982)
		(property "Reference" "TP141"
			(at 0 0 0)
			(layer "B.SilkS")
			(hide yes)
			(effects
				(font
					(size 1.27 1.27)
				)
				(justify mirror)
			)
		)
		(property "Value" "TPAD28-2-GP"
			(at 0.0127 -1.6637 0)
			(unlocked yes)
			(layer "B.Fab")
			(hide yes)
			(effects
				(font
					(size 1.016 1.016)
					(thickness 0.1524)
				)
				(justify mirror)
			)
		)
		(property "Device Type" "TPAD28"
			(at 0.0127 -3.1877 0)
			(unlocked yes)
			(layer "B.Fab")
			(hide yes)
			(effects
				(font
					(size 1.016 1.016)
					(thickness 0.1524)
				)
				(justify mirror)
			)
		)
		(duplicate_pad_numbers_are_jumpers no)
		(fp_poly
			(pts
				(arc
					(start 0.3556 0)
					(mid -0.3556 0)
					(end 0.3556 0)
				)
			)
			(stroke
				(width 0)
				(type default)
			)
			(fill no)
			(layer "B.CrtYd")
		)
		(fp_poly
			(pts
				(arc
					(start 0.6096 0)
					(mid -0.6096 0)
					(end 0.6096 0)
				)
			)
			(stroke
				(width 0)
				(type default)
			)
			(fill no)
			(layer "B.Fab")
		)
		(pad "1" smd circle
			(at 0 0 180)
			(size 0.7112 0.7112)
			(layers "B.Cu" "B.Mask" "B.Paste")
			(net "OSC_REF_CLK")
		)
	)
	(footprint ""
		(layer "B.Cu")
		(at 124.714 -69.5071 90)
		(property "Reference" "C306"
			(at 0 0 90)
			(layer "B.SilkS")
			(hide yes)
			(effects
				(font
					(size 1.27 1.27)
				)
				(justify mirror)
			)
		)
		(property "Value" "SCD1U6D3V1KX-GP"
			(at 2.8321 -1.7399 90)
			(unlocked yes)
			(layer "B.Fab")
			(hide yes)
			(effects
				(font
					(size 1.016 1.016)
					(thickness 0.1524)
				)
				(justify mirror)
			)
		)
		(property "Device Type" "C0201H13"
			(at 2.8321 -3.2639 90)
			(unlocked yes)
			(layer "B.Fab")
			(hide yes)
			(effects
				(font
					(size 1.016 1.016)
					(thickness 0.1524)
				)
				(justify mirror)
			)
		)
		(duplicate_pad_numbers_are_jumpers no)
		(fp_rect
			(start 0.2794 0.6477)
			(end -0.2794 -0.6477)
			(stroke
				(width 0)
				(type default)
			)
			(fill no)
			(layer "B.CrtYd")
		)
		(fp_rect
			(start 0.2794 0.6477)
			(end -0.2794 -0.6477)
			(stroke
				(width 0)
				(type default)
			)
			(fill no)
			(layer "B.Fab")
		)
		(pad "1" smd custom
			(at 0 -0.2794 270)
			(size 0.0762 0.0762)
			(layers "B.Cu" "B.Mask" "B.Paste")
			(net "GB_VDDA")
			(options
				(clearance outline)
				(anchor circle)
			)
			(primitives
				(gr_poly
					(pts
						(arc
							(start 0.1524 0.127)
							(mid 0.137521 0.162921)
							(end 0.1016 0.1778)
						)
						(arc
							(start -0.1016 0.1778)
							(mid -0.137521 0.162921)
							(end -0.1524 0.127)
						)
						(arc
							(start -0.1524 -0.127)
							(mid -0.137521 -0.162921)
							(end -0.1016 -0.1778)
						)
						(arc
							(start 0.1016 -0.1778)
							(mid 0.137521 -0.162921)
							(end 0.1524 -0.127)
						)
					)
					(width 0)
					(fill yes)
				)
			)
		)
		(pad "2" smd custom
			(at 0 0.2794 270)
			(size 0.0762 0.0762)
			(layers "B.Cu" "B.Mask" "B.Paste")
			(net "GND")
			(options
				(clearance outline)
				(anchor circle)
			)
			(primitives
				(gr_poly
					(pts
						(arc
							(start 0.1524 0.127)
							(mid 0.137521 0.162921)
							(end 0.1016 0.1778)
						)
						(arc
							(start -0.1016 0.1778)
							(mid -0.137521 0.162921)
							(end -0.1524 0.127)
						)
						(arc
							(start -0.1524 -0.127)
							(mid -0.137521 -0.162921)
							(end -0.1016 -0.1778)
						)
						(arc
							(start 0.1016 -0.1778)
							(mid 0.137521 -0.162921)
							(end 0.1524 -0.127)
						)
					)
					(width 0)
					(fill yes)
				)
			)
		)
	)
	(footprint ""
		(layer "B.Cu")
		(at 166.636954 -11.428222)
		(property "Reference" "C740"
			(at 0 0 0)
			(layer "B.SilkS")
			(hide yes)
			(effects
				(font
					(size 1.27 1.27)
				)
				(justify mirror)
			)
		)
		(property "Value" "SCD1U16V2KX-3GP"
			(at -1.1811 -2.7051 0)
			(unlocked yes)
			(layer "B.Fab")
			(hide yes)
			(effects
				(font
					(size 1.016 1.016)
					(thickness 0.1524)
				)
				(justify mirror)
			)
		)
		(property "Device Type" "C402H22"
			(at -1.1811 -4.2291 0)
			(unlocked yes)
			(layer "B.Fab")
			(hide yes)
			(effects
				(font
					(size 1.016 1.016)
					(thickness 0.1524)
				)
				(justify mirror)
			)
		)
		(duplicate_pad_numbers_are_jumpers no)
		(fp_rect
			(start 0.4318 0.9525)
			(end -0.4318 -0.9525)
			(stroke
				(width 0)
				(type default)
			)
			(fill no)
			(layer "B.CrtYd")
		)
		(fp_rect
			(start 0.4318 0.9525)
			(end -0.4318 -0.9525)
			(stroke
				(width 0)
				(type default)
			)
			(fill no)
			(layer "B.Fab")
		)
		(pad "1" smd custom
			(at 0 -0.4445 180)
			(size 0.1524 0.1524)
			(layers "B.Cu" "B.Mask" "B.Paste")
			(net "U50_OE")
			(options
				(clearance outline)
				(anchor circle)
			)
			(primitives
				(gr_poly
					(pts
						(arc
							(start 0.3048 0.2032)
							(mid 0.275042 0.275042)
							(end 0.2032 0.3048)
						)
						(arc
							(start -0.2032 0.3048)
							(mid -0.275042 0.275042)
							(end -0.3048 0.2032)
						)
						(arc
							(start -0.3048 -0.2032)
							(mid -0.275042 -0.275042)
							(end -0.2032 -0.3048)
						)
						(arc
							(start 0.2032 -0.3048)
							(mid 0.275042 -0.275042)
							(end 0.3048 -0.2032)
						)
					)
					(width 0)
					(fill yes)
				)
			)
		)
		(pad "2" smd custom
			(at 0 0.4445 180)
			(size 0.1524 0.1524)
			(layers "B.Cu" "B.Mask" "B.Paste")
			(net "GND")
			(options
				(clearance outline)
				(anchor circle)
			)
			(primitives
				(gr_poly
					(pts
						(arc
							(start 0.3048 0.2032)
							(mid 0.275042 0.275042)
							(end 0.2032 0.3048)
						)
						(arc
							(start -0.2032 0.3048)
							(mid -0.275042 0.275042)
							(end -0.3048 0.2032)
						)
						(arc
							(start -0.3048 -0.2032)
							(mid -0.275042 -0.275042)
							(end -0.2032 -0.3048)
						)
						(arc
							(start 0.2032 -0.3048)
							(mid 0.275042 -0.275042)
							(end 0.3048 -0.2032)
						)
					)
					(width 0)
					(fill yes)
				)
			)
		)
	)
)
